FILE_TYPE = CONNECTIVITY;
{Allegro Design Entry HDL 17.2-2016 S081 (4005846) 1/11/2022}
"PAGE_NUMBER" = 237;
0"NC";
1"P3V3_OCP_V3_2_R\g";
2"P3V3_AUX\g";
3"P12V_OCP_V3_2\g";
4"P12V_AUX\g";
5"P12V_AUX\g";
6"P3V3_AUX\g";
7"P3V3_AUX\g";
8"GND\g";
9"GND\g";
10"GND\g";
11"GND\g";
12"GND\g";
13"GND\g";
14"GND\g";
15"GND\g";
16"GND\g";
17"GND\g";
18"GND\g";
19"GND\g";
20"GND\g";
21"GND\g";
22"GND\g";
23"P12V_OCP_ISET_2";
24"HP_LVC3_OCP_V3_2_P12V_PWRGD";
25"HP_LVC3_OCP_V3_2_EN";
26"P12V_OCP_IMON_2";
27"P12V_OCP_V3_2_ISENSE_MPS_TIC";
28"P12V_OCP_V3_2_ISENSE_MPS_MAM";
29"P12V_OCP_AVIN_PD_2";
30"P12V_OCP_OV_FB_2";
31"P12V_OCP_AVIN_PD_2";
32"P12V_OCP_FLTB_2";
33"P12V_OCP_V3_2_EN_2_R3";
34"P12V_OCP_SS_2";
35"P12V_OCP_TIMER_2";
36"HP_LVC3_OCP_V3_2_EN";
37"P3V3_OCP_MODE_2";
38"P3V3_OCP_EN_2";
39"P3V3_OCP_ILIMIT_2";
40"P3V3_OCP_DVDT_2";
41"P3V3_OCP_GATE_PU207_2";
%"UNIVERSAL_GND"
"1","(-250,5875)","0","logical_power","I34";
;
HDL_POWER"GND"
CDS_LIB"logical_power";
"A"8;
%"Q_CAP"
"1","(-250,6175)","0","pure_quanta","I35";
;
PART_NUMBER"CH0396J0B04"
ROOM"NIC1_P3V3_BOM2"
VOLTAGE"50V"
PACK_TYPE"C0402"
VALUE"39PF"
MATERIAL"EMPTY"
LOCATION"PC2168"
TOLERANCE"5%"
CDS_LIB"pure_quanta"
$SEC"1"
CDS_SEC"1";
"B"
$PN"2"8;
"A"
$PN"1"37;
%"Q_RES"
"2","(150,6175)","0","pure_quanta","I43";
;
PART_NUMBER"CS37152FB05"
ROOM"NIC1_P3V3_BOM2"
MATERIAL"EMPTY"
PACK_TYPE"0402LF"
VALUE"71.5K"
TOLERANCE"1%"
LOCATION"PR3855"
WATTAGE"1/16W"
CDS_LIB"pure_quanta"
$SEC"1"
CDS_SEC"1";
"A"
$PN"1"37;
"B"
$PN"2"8;
%"Q_RES"
"1","(225,6475)","0","pure_quanta","I44";
;
PART_NUMBER"CS00002JB13"
ROOM"NIC1_P3V3_BOM2"
TOLERANCE"5%"
VALUE"0"
PACK_TYPE"0402LF"
WATTAGE"1/16W"
MATERIAL"EMPTY"
$LOCATION"R3631"
CDS_LIB"pure_quanta"
CDS_LOCATION"R3631"
$SEC"1"
CDS_SEC"1";
"B"
$PN"2"38;
"A"
$PN"1"25;
%"UNIVERSAL_GND"
"1","(495,5883)","0","logical_power","I45";
;
HDL_POWER"GND"
CDS_LIB"logical_power";
"A"9;
%"Q_RES"
"1","(495,6158)","1","pure_quanta","I46";
;
PART_NUMBER"CS21332FB05"
ROOM"NIC1_P3V3_BOM2"
MATERIAL"EMPTY"
VALUE"1.33K"
PACK_TYPE"0402LF"
TOLERANCE"1%"
LOCATION"PR3856"
WATTAGE"1/16W"
CDS_LIB"pure_quanta"
$SEC"1"
CDS_SEC"1";
"B"
$PN"2"39;
"A"
$PN"1"9;
%"UNIVERSAL_GND"
"1","(470,6533)","0","logical_power","I47";
;
HDL_POWER"GND"
CDS_LIB"logical_power";
"A"10;
%"Q_CAP"
"1","(470,6758)","0","pure_quanta","I48";
;
PART_NUMBER"CH5104KEB02"
ROOM"NIC1_P3V3_BOM2"
VALUE"1UF"
TOLERANCE"10%"
VOLTAGE"25V"
PACK_TYPE"C0402"
MATERIAL"EMPTY"
LOCATION"PC2169"
CDS_LIB"pure_quanta"
$SEC"1"
CDS_SEC"1";
"B"
$PN"2"10;
"A"
$PN"1"2;
%"UNIVERSAL_GND"
"1","(870,5883)","0","logical_power","I49";
;
HDL_POWER"GND"
CDS_LIB"logical_power";
"A"11;
%"Q_CAP"
"1","(870,6108)","0","pure_quanta","I50";
;
PART_NUMBER"CH3683K1B09"
ROOM"NIC1_P3V3_BOM2"
VOLTAGE"16V"
PACK_TYPE"0402"
MATERIAL"EMPTY"
VALUE"0.068UF"
LOCATION"PC1321"
TOLERANCE"10%"
CDS_LIB"pure_quanta"
$SEC"1"
CDS_SEC"1";
"B"
$PN"2"11;
"A"
$PN"1"40;
%"MP5016GQHLZ"
"1","(1675,6425)","0","pure_quanta","I51";
;
PART_NUMBER"AL005016007"
ROOM"NIC1_P3V3_BOM2"
VALUE"MP5016GQH-L-Z"
PART_TYPE"SMLF"
MATERIAL"EMPTY"
LOCATION"PU207"
CDS_LIB"pure_quanta"
CDS_LMAN_SYM_OUTLINE"-250,200,250,-200"
NEEDS_NO_SIZE"TRUE"
$SEC"1"
CDS_SEC"1";
"SOURCE"
$PN"6_7"1;
"GATE"
$PN"8"41;
"DV_DT"
$PN"10"40;
"VCC"
$PN"1_2"2;
"GND"
$PN"3"12;
"ILIMIT"
$PN"4"39;
"MODE"
$PN"5"37;
"EN"
$PN"9"38;
%"UNIVERSAL_POWER"
"1","(470,7083)","2","logical_power","I52";
;
HDL_POWER"P3V3_AUX"
CDS_LIB"logical_power";
"A"2;
%"UNIVERSAL_GND"
"1","(2500,5800)","0","logical_power","I53";
;
HDL_POWER"GND"
CDS_LIB"logical_power";
"A"12;
%"Q_CAP"
"1","(2500,6150)","0","pure_quanta","I54";
;
PART_NUMBER"CH11006JB18"
ROOM"NIC1_P3V3_BOM2"
MATERIAL"EMPTY"
PACK_TYPE"0402"
VOLTAGE"50V"
VALUE"100PF"
LOCATION"PC1322"
CDS_LIB"pure_quanta"
TOLERANCE"5%"
$SEC"1"
CDS_SEC"1";
"B"
$PN"2"12;
"A"
$PN"1"41;
%"UNIVERSAL_GND"
"1","(2900,6000)","0","logical_power","I55";
;
HDL_POWER"GND"
CDS_LIB"logical_power";
"A"13;
%"Q_CAP"
"1","(2900,6350)","0","pure_quanta","I56";
;
PART_NUMBER"CH6103KEA01"
ROOM"NIC1_P3V3_BOM2"
TOLERANCE"10%"
MATERIAL"EMPTY"
PACK_TYPE"C0805"
VALUE"10UF"
VOLTAGE"16V"
LOCATION"PC2173"
CDS_LIB"pure_quanta"
$SEC"1"
CDS_SEC"1";
"B"
$PN"2"13;
"A"
$PN"1"1;
%"UNIVERSAL_POWER"
"1","(2900,6900)","2","logical_power","I57";
;
HDL_POWER"P3V3_OCP_V3_2_R"
CDS_LIB"logical_power";
"A"1;
%"GND"
"1","(-4175,2375)","0","logical_power","I59";
;
SIZE"1B"
CDS_LIB"logical_power"
HDL_POWER"GND";
"A<SIZE-1..0>\NAC"22;
%"GND"
"1","(-3750,2300)","0","logical_power","I60";
;
CDS_LIB"logical_power"
SIZE"1B"
HDL_POWER"GND";
"A<SIZE-1..0>\NAC"21;
%"Q_RES"
"2","(-3750,2575)","0","pure_quanta","I61";
;
PART_NUMBER"CS31432FB02"
ROOM"NIC1_P12V_MPS_MAM_BOM3"
VALUE"14.3K"
MATERIAL"CHIP"
TOLERANCE"1%"
PACK_TYPE"0402LF"
WATTAGE"1/16W"
LOCATION"PR3847"
ROOM1"NIC1_P12V_MPS_TIC_BOM4"
CDS_LIB"pure_quanta"
$SEC"1"
CDS_SEC"1";
"A"
$PN"1"23;
"B"
$PN"2"21;
%"Q_CAP"
"1","(-4175,2725)","0","pure_quanta","I62";
;
PART_NUMBER"CH4223K1B00"
PACK_TYPE"0402"
MATERIAL"X7R"
ROOM"NIC1_P12V_MPS_MAM_BOM3"
VALUE"0.22UF"
VOLTAGE"16V"
LOCATION"PC2164"
ROOM1"NIC1_P12V_MPS_TIC_BOM4"
CDS_LIB"pure_quanta"
TOLERANCE"10%"
$SEC"1"
CDS_SEC"1";
"B"
$PN"2"22;
"A"
$PN"1"35;
%"GND"
"1","(-3775,2925)","0","logical_power","I63";
;
SIZE"1B"
CDS_LIB"logical_power"
HDL_POWER"GND";
"A<SIZE-1..0>\NAC"20;
%"GND"
"1","(-3330,2258)","0","logical_power","I64";
;
CDS_LIB"logical_power"
SIZE"1B"
HDL_POWER"GND";
"A<SIZE-1..0>\NAC"19;
%"Q_CAP"
"1","(-3330,2508)","0","pure_quanta","I65";
;
PART_NUMBER"CH3474K1B04"
ROOM"NIC1_P12V_MPS_MAM_BOM3"
PACK_TYPE"C0402"
VOLTAGE"25V"
MATERIAL"X7R"
VALUE"0.047UF"
LOCATION"PC2166"
ROOM1"NIC1_P12V_MPS_TIC_BOM4"
CDS_LIB"pure_quanta"
TOLERANCE"10%"
$SEC"1"
CDS_SEC"1";
"B"
$PN"2"19;
"A"
$PN"1"34;
%"Q_RES"
"1","(-4075,3175)","0","pure_quanta","I66";
;
PART_NUMBER"CS00002JB13"
ROOM"NIC1_P12V_MPS_MAM_BOM3"
PACK_TYPE"0402LF"
MATERIAL"CHIP"
WATTAGE"1/16W"
VALUE"0"
TOLERANCE"5%"
$LOCATION"R3630"
ROOM1"NIC1_P12V_MPS_TIC_BOM4"
CDS_LIB"pure_quanta"
CDS_LOCATION"R3630"
$SEC"1"
CDS_SEC"1";
"B"
$PN"2"33;
"A"
$PN"1"36;
%"GND"
"1","(-3500,3300)","0","logical_power","I67";
;
SIZE"1B"
CDS_LIB"logical_power"
HDL_POWER"GND";
"A<SIZE-1..0>\NAC"18;
%"Q_CAP"
"1","(-3500,3675)","0","pure_quanta","I68";
;
PART_NUMBER"CH5104KEB02"
ROOM"NIC1_P12V_MPS_MAM_BOM3"
MATERIAL"X6S"
PACK_TYPE"C0402"
VOLTAGE"25V"
VALUE"1UF"
LOCATION"PC2165"
ROOM1"NIC1_P12V_MPS_TIC_BOM4"
CDS_LIB"pure_quanta"
TOLERANCE"10%"
$SEC"1"
CDS_SEC"1";
"B"
$PN"2"18;
"A"
$PN"1"5;
%"GND"
"1","(-3009,2441)","0","logical_power","I69";
;
SIZE"1B"
CDS_LIB"logical_power"
HDL_POWER"GND";
"A<SIZE-1..0>\NAC"17;
%"RS31312R"
"1","(-2550,3050)","0","pure_quanta","I70";
;
PART_NUMBER"AL031312000"
ROOM"NIC1_P12V_MPS_MAM_BOM3"
VALUE"RS31312R"
MATERIAL"IC"
LOCATION"PU206"
ROOM1"NIC1_P12V_MPS_TIC_BOM4"
PART_TYPE"SMLF"
CDS_LIB"pure_quanta"
NEEDS_NO_SIZE"TRUE"
CDS_LMAN_SYM_OUTLINE"-250,525,250,-525"
$SEC"1"
CDS_SEC"1";
"GND"
$PN"7"17;
"SS"
$PN"6"34;
"ISET"
$PN"5"23;
"TIMER"
$PN"4"35;
"ENTM"
$PN"3"20;
"LOADEN"
$PN"2"20;
"EN"
$PN"1"33;
"VIN_26"
$PN"26"5;
"VIN_25"
$PN"25"5;
"VIN_24"
$PN"24"5;
"VIN_23"
$PN"23"5;
"IMON"
$PN"8"26;
"FLTB"
$PN"9"32;
"PG"
$PN"10"24;
"OV"
$PN"11"30;
"VOUT_13"
$PN"13"3;
"AVIN"
$PN"12"29;
"VOUT_14"
$PN"14"3;
"VOUT_15"
$PN"15"3;
"VOUT_16"
$PN"16"3;
"VOUT_17"
$PN"17"3;
"VOUT_18"
$PN"18"3;
"VOUT_19"
$PN"19"3;
"VIN_21_22"
$PN"21_22"5;
"VOUT_20"
$PN"20"3;
%"GND"
"1","(-1550,1950)","0","logical_power","I71";
;
CDS_LIB"logical_power"
SIZE"1B"
HDL_POWER"GND";
"A<SIZE-1..0>\NAC"16;
%"Q_RES"
"2","(-2000,2325)","0","pure_quanta","I72";
;
PART_NUMBER"CS31742FB04"
ROOM"NIC1_P12V_MPS_MAM_BOM3"
MATERIAL"CHIP"
PACK_TYPE"0402LF"
WATTAGE"1/16W"
TOLERANCE"1%"
VALUE"17.4K"
LOCATION"PR3849"
ROOM1"NIC1_P12V_MPS_TIC_BOM4"
CDS_LIB"pure_quanta"
$SEC"1"
CDS_SEC"1";
"A"
$PN"1"26;
"B"
$PN"2"16;
%"Q_CAP"
"1","(-1550,2325)","0","pure_quanta","I73";
;
PART_NUMBER"CH11006JB18"
ROOM"NIC1_P12V_MPS_MAM_BOM3"
VOLTAGE"50V"
MATERIAL"X7R"
PACK_TYPE"0402"
VALUE"100PF"
LOCATION"PC2167"
ROOM1"NIC1_P12V_MPS_TIC_BOM4"
CDS_LIB"pure_quanta"
TOLERANCE"5%"
$SEC"1"
CDS_SEC"1";
"B"
$PN"2"16;
"A"
$PN"1"26;
%"Q_RES"
"1","(-1425,2675)","0","pure_quanta","I74";
;
PART_NUMBER"CS31002FB08"
ROOM"NIC1_P12V_MPS_MAM_BOM3"
TOLERANCE"1%"
VALUE"10K"
WATTAGE"1/16W"
PACK_TYPE"0402LF"
MATERIAL"CHIP"
LOCATION"PR3851"
ROOM1"NIC1_P12V_MPS_TIC_BOM4"
CDS_LIB"pure_quanta"
$SEC"1"
CDS_SEC"1";
"B"
$PN"2"6;
"A"
$PN"1"32;
%"Q_RES"
"2","(-2050,3725)","0","pure_quanta","I75";
;
PART_NUMBER"CS31002FB08"
ROOM"NIC1_P12V_MPS_MAM_BOM3"
PACK_TYPE"0402LF"
VALUE"10K"
TOLERANCE"1%"
WATTAGE"1/16W"
MATERIAL"CHIP"
$LOCATION"R3848"
ROOM1"NIC1_P12V_MPS_TIC_BOM4"
CDS_LIB"pure_quanta"
CDS_LOCATION"R3848"
$SEC"1"
CDS_SEC"1";
"A"
$PN"1"7;
"B"
$PN"2"24;
%"VCCAUX15"
"1","(-2050,3950)","0","logical_power","I76";
;
HDL_POWER"P3V3_AUX"
CDS_LIB"logical_power";
"A"7;
%"Q_RES"
"2","(-1500,3150)","0","pure_quanta","I77";
;
PART_NUMBER"CS11002FB07"
PACK_TYPE"0402LF"
VALUE"100"
TOLERANCE"1%"
WATTAGE"1/16W"
MATERIAL"EMPTY"
LOCATION"PR3850"
CDS_LIB"pure_quanta"
$SEC"1"
CDS_SEC"1";
"A"
$PN"1"3;
"B"
$PN"2"29;
%"VCCAUX15"
"1","(-1155,2733)","0","logical_power","I79";
;
HDL_POWER"P3V3_AUX"
CDS_LIB"logical_power";
"A"6;
%"Q_RES"
"1","(-150,2075)","0","pure_quanta","I80";
;
PART_NUMBER"CS00002JB13"
ROOM1"NIC1_P12V_MPS_TIC_BOM4"
VALUE"0"
MATERIAL"CHIP"
PACK_TYPE"0402LF"
TOLERANCE"5%"
WATTAGE"1/16W"
$LOCATION"R3874"
CDS_LIB"pure_quanta"
CDS_LOCATION"R3874"
$SEC"1"
CDS_SEC"1";
"B"
$PN"2"27;
"A"
$PN"1"26;
%"Q_RES"
"1","(-150,2200)","0","pure_quanta","I81";
;
PART_NUMBER"CS00002JB13"
ROOM"NIC1_P12V_MPS_MAM_BOM3"
TOLERANCE"5%"
VALUE"0"
WATTAGE"1/16W"
MATERIAL"EMPTY"
PACK_TYPE"0402LF"
$LOCATION"R3873"
CDS_LIB"pure_quanta"
CDS_LOCATION"R3873"
$SEC"1"
CDS_SEC"1";
"B"
$PN"2"28;
"A"
$PN"1"26;
%"GND"
"1","(-355,2333)","0","logical_power","I82";
;
CDS_LIB"logical_power"
SIZE"1B"
HDL_POWER"GND";
"A<SIZE-1..0>\NAC"15;
%"Q_RES"
"2","(-555,2658)","0","pure_quanta","I83";
;
PART_NUMBER"CS31002FB08"
ROOM"NIC1_P12V_MPS_MAM_BOM3"
WATTAGE"1/16W"
PACK_TYPE"0402LF"
VALUE"10K"
MATERIAL"CHIP"
TOLERANCE"1%"
LOCATION"PR3854"
ROOM1"NIC1_P12V_MPS_TIC_BOM4"
CDS_LIB"pure_quanta"
$SEC"1"
CDS_SEC"1";
"A"
$PN"1"30;
"B"
$PN"2"15;
%"Q_RES"
"2","(-555,3083)","0","pure_quanta","I84";
;
PART_NUMBER"CS41202FB05"
ROOM"NIC1_P12V_MPS_MAM_BOM3"
WATTAGE"1/16W"
TOLERANCE"1%"
PACK_TYPE"0402LF"
MATERIAL"CHIP"
VALUE"120K"
LOCATION"PR3853"
ROOM1"NIC1_P12V_MPS_TIC_BOM4"
CDS_LIB"pure_quanta"
$SEC"1"
CDS_SEC"1";
"A"
$PN"1"4;
"B"
$PN"2"30;
%"Q_RES"
"2","(-950,3150)","0","pure_quanta","I85";
;
PART_NUMBER"CS37152FB05"
MATERIAL"EMPTY"
VALUE"71.5K"
TOLERANCE"1%"
PACK_TYPE"0402LF"
LOCATION"PR3852"
CDS_LIB"pure_quanta"
WATTAGE"1/16W"
$SEC"1"
CDS_SEC"1";
"A"
$PN"1"3;
"B"
$PN"2"30;
%"UNIVERSAL_POWER"
"1","(-3500,4100)","0","logical_power","I86";
;
HDL_POWER"P12V_AUX"
CDS_LIB"logical_power";
"A"5;
%"Q_RES"
"2","(-25,3075)","0","pure_quanta","I87";
;
PART_NUMBER"CS04993F909"
ROOM"NIC1_P12V_MPS_MAM_BOM3"
TOLERANCE"1%"
PACK_TYPE"0603LF"
MATERIAL"CHIP"
WATTAGE"1/10W"
VALUE"49.9"
LOCATION"PR3857"
ROOM1"NIC1_P12V_MPS_TIC_BOM4"
CDS_LIB"pure_quanta"
$SEC"1"
CDS_SEC"1";
"A"
$PN"1"4;
"B"
$PN"2"31;
%"UNIVERSAL_POWER"
"1","(-75,3350)","0","logical_power","I89";
;
HDL_POWER"P12V_AUX"
CDS_LIB"logical_power";
"A"4;
%"GND"
"1","(475,3075)","0","logical_power","I90";
;
SIZE"1B"
CDS_LIB"logical_power"
HDL_POWER"GND";
"A<SIZE-1..0>\NAC"14;
%"Q_CAP"
"1","(475,3325)","2","pure_quanta","I91";
;
PART_NUMBER"CH4104K1B00"
ROOM"NIC1_P12V_MPS_MAM_BOM3"
MATERIAL"X7R"
PACK_TYPE"0402"
VALUE"0.1UF"
VOLTAGE"25V"
TOLERANCE"10%"
LOCATION"PC2174"
ROOM1"NIC1_P12V_MPS_TIC_BOM4"
CDS_LIB"pure_quanta"
$SEC"1"
CDS_SEC"1";
"B"
$PN"2"14;
"A"
$PN"1"3;
%"UNIVERSAL_POWER"
"1","(475,3625)","2","logical_power","I92";
;
HDL_POWER"P12V_OCP_V3_2"
CDS_LIB"logical_power";
"A"3;
%"Q_CAP"
"1","(-25,2650)","0","pure_quanta","I95";
;
PART_NUMBER"CH5223M1900"
ROOM"NIC1_P12V_MPS_MAM_BOM3"
VOLTAGE"16V"
VALUE"2.2UF"
MATERIAL"X7R"
PACK_TYPE"C0603"
TOLERANCE"20%"
LOCATION"PC1320"
ROOM1"NIC1_P12V_MPS_TIC_BOM4"
CDS_LIB"pure_quanta"
$SEC"1"
CDS_SEC"1";
"B"
$PN"2"15;
"A"
$PN"1"31;
END.
